FILE_TYPE = MACRO_DRAWING;
SET COLOR_WIRE YELLOW;
SET COLOR_PROP ORANGE;
SET COLOR_DOT WHITE;
SET COLOR_ARC YELLOW;
SET COLOR_BODY GREEN;
SET COLOR_NOTE PURPLE;
SET PROP_DISPLAY VALUE;
SET PAGE_NUMBER P265;
FORCEADD UNIVERSAL_GND..1
(-9000 1625);
FORCEPROP 3 LASTPIN (-9000 1675) SIG_NAME GND\g
J 0
(-8990 1685);
DISPLAY 0.659574 (-8990 1685);
PAINT MONO (-8990 1685);
DISPLAY INVISIBLE (-8990 1685);
FORCEPROP 1 LAST HDL_POWER GND
J 1
(-8975 1550);
DISPLAY 0.872340 (-8975 1550);
PAINT GREEN (-8975 1550);
DISPLAY INVISIBLE (-8975 1550);
FORCEPROP 2 LAST CDS_LIB logical_power
J 0
(-9000 1625);
PAINT MONO (-9000 1625);
DISPLAY INVISIBLE (-9000 1625);
FORCEPROP 1 LAST PATH I1
J 0
(-8925 1625);
DISPLAY 0.872340 (-8925 1625);
PAINT AQUA (-8925 1625);
DISPLAY INVISIBLE (-8925 1625);
FORCEADD UNIVERSAL_GND..1
(-8225 2125);
FORCEPROP 3 LASTPIN (-8225 2175) SIG_NAME GND\g
J 0
(-8215 2185);
DISPLAY 0.659574 (-8215 2185);
PAINT MONO (-8215 2185);
DISPLAY INVISIBLE (-8215 2185);
FORCEPROP 1 LAST HDL_POWER GND
J 1
(-8200 2050);
DISPLAY 0.872340 (-8200 2050);
PAINT GREEN (-8200 2050);
DISPLAY INVISIBLE (-8200 2050);
FORCEPROP 2 LAST CDS_LIB logical_power
J 0
(-8225 2125);
PAINT MONO (-8225 2125);
DISPLAY INVISIBLE (-8225 2125);
FORCEPROP 1 LAST PATH I10
J 0
(-8150 2125);
DISPLAY 0.872340 (-8150 2125);
PAINT AQUA (-8150 2125);
DISPLAY INVISIBLE (-8150 2125);
FORCEADD Q_CAP..1
(-8225 2375);
FORCEPROP 1 LAST PART_NUMBER CH5222KEB01
J 0
(-8175 2200);
DISPLAY 0.617021 (-8175 2200);
PAINT BLUE (-8175 2200);
DISPLAY INVISIBLE (-8175 2200);
FORCEPROP 1 LAST PACK_TYPE C0402
J 0
(-8175 2250);
DISPLAY 0.617021 (-8175 2250);
PAINT SKYBLUE (-8175 2250);
FORCEPROP 1 LAST MATERIAL X6S
J 0
(-8175 2300);
DISPLAY 0.617021 (-8175 2300);
PAINT SKYBLUE (-8175 2300);
FORCEPROP 1 LAST VOLTAGE 10V
J 0
(-8175 2400);
DISPLAY 0.617021 (-8175 2400);
PAINT SKYBLUE (-8175 2400);
FORCEPROP 1 LAST TOLERANCE 10%
J 0
(-8175 2350);
DISPLAY 0.617021 (-8175 2350);
PAINT SKYBLUE (-8175 2350);
FORCEPROP 1 LAST VALUE 2.2UF
J 0
(-8175 2450);
DISPLAY 0.617021 (-8175 2450);
PAINT SKYBLUE (-8175 2450);
FORCEPROP 1 LAST LOCATION PC633
J 0
(-8175 2500);
DISPLAY 0.617021 (-8175 2500);
PAINT AQUA (-8175 2500);
FORCEPROP 1 LASTPIN (-8225 2475) $PN 1
J 0
(-8215 2455);
DISPLAY 0.617021 (-8215 2455);
PAINT MONO (-8215 2455);
FORCEPROP 1 LASTPIN (-8225 2275) $PN 2
J 0
(-8215 2255);
DISPLAY 0.617021 (-8215 2255);
PAINT MONO (-8215 2255);
FORCEPROP 2 LAST CDS_LIB pure_quanta
J 0
(-8225 2375);
DISPLAY INVISIBLE (-8225 2375);
FORCEPROP 1 LAST PATH I11
J 0
(-8175 2525);
DISPLAY 0.978723 (-8175 2525);
PAINT WHITE (-8175 2525);
DISPLAY INVISIBLE (-8175 2525);
FORCEPROP 1 LAST LOCATION PC633
J 0
(-8175 2550);
DISPLAY 1.021277 (-8175 2550);
PAINT AQUA (-8175 2550);
DISPLAY INVISIBLE (-8175 2550);
FORCEPROP 0 LAST $SEC 1
J 0
(-8175 2550);
DISPLAY 0.680851 (-8175 2550);
PAINT MONO (-8175 2550);
DISPLAY INVISIBLE (-8175 2550);
FORCEPROP 0 LAST CDS_SEC 1
J 0
(-8175 2550);
DISPLAY 1.021277 (-8175 2550);
DISPLAY INVISIBLE (-8175 2550);
FORCEADD Q_RES..2
(-8225 2775);
FORCEPROP 1 LAST PART_NUMBER CS-2202FB01
J 0
(-8185 2650);
DISPLAY 0.617021 (-8185 2650);
PAINT BLUE (-8185 2650);
DISPLAY INVISIBLE (-8185 2650);
FORCEPROP 1 LAST WATTAGE 1/16W
J 0
(-8185 2750);
DISPLAY 0.617021 (-8185 2750);
PAINT SKYBLUE (-8185 2750);
FORCEPROP 1 LAST TOLERANCE 1%
J 0
(-8180 2800);
DISPLAY 0.617021 (-8180 2800);
PAINT SKYBLUE (-8180 2800);
FORCEPROP 1 LAST VALUE 2.2
J 0
(-8180 2850);
DISPLAY 0.617021 (-8180 2850);
PAINT SKYBLUE (-8180 2850);
FORCEPROP 1 LAST PACK_TYPE 0402LF
J 0
(-8185 2600);
DISPLAY 0.617021 (-8185 2600);
PAINT SKYBLUE (-8185 2600);
FORCEPROP 1 LAST MATERIAL CHIP
J 0
(-8185 2700);
DISPLAY 0.617021 (-8185 2700);
PAINT SKYBLUE (-8185 2700);
FORCEPROP 1 LAST LOCATION PR380
J 0
(-8180 2900);
DISPLAY 0.617021 (-8180 2900);
PAINT AQUA (-8180 2900);
FORCEPROP 1 LASTPIN (-8225 2875) $PN 1
J 0
(-8220 2837);
DISPLAY 0.617021 (-8220 2837);
PAINT MONO (-8220 2837);
FORCEPROP 1 LASTPIN (-8225 2675) $PN 2
J 0
(-8220 2685);
DISPLAY 0.617021 (-8220 2685);
PAINT MONO (-8220 2685);
FORCEPROP 2 LAST CDS_LIB pure_quanta
J 0
(-8225 2775);
DISPLAY INVISIBLE (-8225 2775);
FORCEPROP 1 LAST PATH I12
J 0
(-8175 2950);
DISPLAY 0.978723 (-8175 2950);
PAINT WHITE (-8175 2950);
DISPLAY INVISIBLE (-8175 2950);
FORCEPROP 1 LAST LOCATION PR380
J 0
(-8175 2950);
DISPLAY 1.021277 (-8175 2950);
PAINT AQUA (-8175 2950);
DISPLAY INVISIBLE (-8175 2950);
FORCEPROP 0 LAST $SEC 1
J 0
(-8175 2950);
DISPLAY 0.680851 (-8175 2950);
PAINT MONO (-8175 2950);
DISPLAY INVISIBLE (-8175 2950);
FORCEPROP 0 LAST CDS_SEC 1
J 0
(-8175 2950);
DISPLAY 1.021277 (-8175 2950);
DISPLAY INVISIBLE (-8175 2950);
FORCEADD UNIVERSAL_GND..1
(-7575 2575);
FORCEPROP 3 LASTPIN (-7575 2625) SIG_NAME GND\g
J 0
(-7565 2635);
DISPLAY 0.659574 (-7565 2635);
PAINT MONO (-7565 2635);
DISPLAY INVISIBLE (-7565 2635);
FORCEPROP 1 LAST HDL_POWER GND
J 1
(-7550 2500);
DISPLAY 0.872340 (-7550 2500);
PAINT GREEN (-7550 2500);
DISPLAY INVISIBLE (-7550 2500);
FORCEPROP 2 LAST CDS_LIB logical_power
J 0
(-7575 2575);
DISPLAY INVISIBLE (-7575 2575);
FORCEPROP 1 LAST PATH I13
J 0
(-7500 2575);
DISPLAY 0.872340 (-7500 2575);
PAINT AQUA (-7500 2575);
DISPLAY INVISIBLE (-7500 2575);
FORCEADD Q_CAP..1
(-7575 2800);
FORCEPROP 1 LAST PART_NUMBER CH5222KEB01
J 0
(-7525 2725);
DISPLAY 0.638298 (-7525 2725);
DISPLAY INVISIBLE (-7525 2725);
FORCEPROP 1 LAST PACK_TYPE C0402
J 0
(-7525 2675);
DISPLAY 0.638298 (-7525 2675);
FORCEPROP 1 LAST VALUE 2.2UF
J 0
(-7525 2925);
DISPLAY 0.638298 (-7525 2925);
FORCEPROP 1 LAST VOLTAGE 10V
J 0
(-7525 2875);
DISPLAY 0.638298 (-7525 2875);
FORCEPROP 1 LAST MATERIAL X6S
J 0
(-7525 2775);
DISPLAY 0.638298 (-7525 2775);
FORCEPROP 1 LAST TOLERANCE 10%
J 0
(-7525 2825);
DISPLAY 0.638298 (-7525 2825);
FORCEPROP 1 LAST LOCATION PC2948
J 0
(-7525 2975);
DISPLAY 0.638298 (-7525 2975);
FORCEPROP 1 LASTPIN (-7575 2900) $PN 1
J 0
(-7565 2880);
DISPLAY 0.787234 (-7565 2880);
PAINT MONO (-7565 2880);
FORCEPROP 1 LASTPIN (-7575 2700) $PN 2
J 0
(-7565 2680);
DISPLAY 0.787234 (-7565 2680);
PAINT MONO (-7565 2680);
FORCEPROP 2 LAST CDS_LIB pure_quanta
J 0
(-7575 2800);
DISPLAY INVISIBLE (-7575 2800);
FORCEPROP 1 LAST PATH I14
J 0
(-7525 2950);
DISPLAY 0.978723 (-7525 2950);
PAINT WHITE (-7525 2950);
DISPLAY INVISIBLE (-7525 2950);
FORCEPROP 0 LAST $SEC 1
J 0
(-7525 3025);
DISPLAY 0.680851 (-7525 3025);
PAINT MONO (-7525 3025);
DISPLAY INVISIBLE (-7525 3025);
FORCEPROP 0 LAST CDS_SEC 1
J 0
(-7525 3025);
DISPLAY 1.021277 (-7525 3025);
DISPLAY INVISIBLE (-7525 3025);
FORCEADD VCC15..1
(-8225 3350);
FORCEPROP 1 LAST HDL_POWER PVCCFA_EHV_CPU0_PVCC
J 1
(-8225 3400);
DISPLAY 0.617021 (-8225 3400);
PAINT GREEN (-8225 3400);
FORCEPROP 2 LAST CDS_LIB logical_power
J 0
(-8225 3350);
DISPLAY INVISIBLE (-8225 3350);
FORCEPROP 1 LAST PATH I15
J 0
(-8175 3375);
DISPLAY 0.872340 (-8175 3375);
PAINT AQUA (-8175 3375);
DISPLAY INVISIBLE (-8175 3375);
FORCEADD UNIVERSAL_GND..1
(-6050 1200);
FORCEPROP 3 LASTPIN (-6050 1250) SIG_NAME GND\g
J 0
(-6040 1260);
DISPLAY 0.659574 (-6040 1260);
PAINT MONO (-6040 1260);
DISPLAY INVISIBLE (-6040 1260);
FORCEPROP 1 LAST HDL_POWER GND
J 1
(-6025 1125);
DISPLAY 0.872340 (-6025 1125);
PAINT GREEN (-6025 1125);
DISPLAY INVISIBLE (-6025 1125);
FORCEPROP 2 LAST CDS_LIB logical_power
J 0
(-6050 1200);
PAINT MONO (-6050 1200);
DISPLAY INVISIBLE (-6050 1200);
FORCEPROP 1 LAST PATH I16
J 0
(-5975 1200);
DISPLAY 0.872340 (-5975 1200);
PAINT AQUA (-5975 1200);
DISPLAY INVISIBLE (-5975 1200);
FORCEADD Q_RES..1
(-5150 1675);
FORCEPROP 1 LAST PART_NUMBER CS00002JB13
J 0
(-5275 1475);
DISPLAY 0.617021 (-5275 1475);
PAINT BLUE (-5275 1475);
DISPLAY INVISIBLE (-5275 1475);
FORCEPROP 1 LAST MATERIAL CHIP
J 0
(-5275 1600);
DISPLAY 0.617021 (-5275 1600);
PAINT SKYBLUE (-5275 1600);
FORCEPROP 1 LAST WATTAGE 1/16W
J 2
(-5125 1525);
DISPLAY 0.617021 (-5125 1525);
PAINT SKYBLUE (-5125 1525);
FORCEPROP 1 LAST PACK_TYPE 0402LF
J 0
(-5275 1550);
DISPLAY 0.617021 (-5275 1550);
PAINT SKYBLUE (-5275 1550);
FORCEPROP 1 LAST TOLERANCE 5%
J 0
(-5000 1675);
DISPLAY 0.617021 (-5000 1675);
PAINT SKYBLUE (-5000 1675);
FORCEPROP 1 LAST VALUE 0
J 2
(-5025 1675);
DISPLAY 0.617021 (-5025 1675);
PAINT SKYBLUE (-5025 1675);
FORCEPROP 1 LAST LOCATION PR1785
J 0
(-5400 1675);
DISPLAY 0.617021 (-5400 1675);
PAINT AQUA (-5400 1675);
FORCEPROP 1 LASTPIN (-5250 1675) $PN 1
J 0
(-5238 1687);
DISPLAY 0.617021 (-5238 1687);
FORCEPROP 1 LASTPIN (-5050 1675) $PN 2
J 0
(-5088 1687);
DISPLAY 0.617021 (-5088 1687);
FORCEPROP 2 LAST CDS_LIB pure_quanta
J 0
(-5150 1675);
PAINT MONO (-5150 1675);
DISPLAY INVISIBLE (-5150 1675);
FORCEPROP 1 LAST PATH I17
J 0
(-5200 1825);
DISPLAY 0.978723 (-5200 1825);
PAINT WHITE (-5200 1825);
DISPLAY INVISIBLE (-5200 1825);
FORCEPROP 2 LAST $SEC 1
J 0
(-5200 1875);
DISPLAY 0.680851 (-5200 1875);
PAINT MONO (-5200 1875);
DISPLAY INVISIBLE (-5200 1875);
FORCEPROP 2 LAST CDS_SEC 1
J 0
(-5200 1875);
DISPLAY 1.021277 (-5200 1875);
DISPLAY INVISIBLE (-5200 1875);
FORCEADD Q_CAP..1
(-5900 2825);
FORCEPROP 1 LAST PART_NUMBER TMP_QCH2336K1B12
J 0
(-5850 2675);
DISPLAY 0.617021 (-5850 2675);
PAINT BLUE (-5850 2675);
DISPLAY INVISIBLE (-5850 2675);
FORCEPROP 1 LAST TOLERANCE 10%
J 0
(-5850 2825);
DISPLAY 0.617021 (-5850 2825);
PAINT SKYBLUE (-5850 2825);
FORCEPROP 1 LAST VOLTAGE 50V
J 0
(-5850 2875);
DISPLAY 0.617021 (-5850 2875);
PAINT SKYBLUE (-5850 2875);
FORCEPROP 1 LAST PACK_TYPE 0402
J 0
(-5850 2725);
DISPLAY 0.617021 (-5850 2725);
PAINT SKYBLUE (-5850 2725);
FORCEPROP 1 LAST MATERIAL X7R
J 0
(-5850 2775);
DISPLAY 0.617021 (-5850 2775);
PAINT SKYBLUE (-5850 2775);
FORCEPROP 1 LAST VALUE 3300PF
J 0
(-5850 2925);
DISPLAY 0.617021 (-5850 2925);
PAINT SKYBLUE (-5850 2925);
FORCEPROP 1 LAST LOCATION PC634
J 0
(-5850 2975);
DISPLAY 0.617021 (-5850 2975);
PAINT AQUA (-5850 2975);
FORCEPROP 1 LASTPIN (-5900 2925) $PN 1
J 0
(-5890 2905);
DISPLAY 0.617021 (-5890 2905);
PAINT MONO (-5890 2905);
FORCEPROP 1 LASTPIN (-5900 2725) $PN 2
J 0
(-5890 2705);
DISPLAY 0.617021 (-5890 2705);
PAINT MONO (-5890 2705);
FORCEPROP 2 LAST CDS_LIB pure_quanta
J 0
(-5900 2825);
DISPLAY INVISIBLE (-5900 2825);
FORCEPROP 1 LAST PATH I18
J 0
(-5850 2975);
DISPLAY 0.978723 (-5850 2975);
PAINT WHITE (-5850 2975);
DISPLAY INVISIBLE (-5850 2975);
FORCEPROP 1 LAST LOCATION PC634
J 0
(-5850 3025);
DISPLAY 1.021277 (-5850 3025);
PAINT AQUA (-5850 3025);
DISPLAY INVISIBLE (-5850 3025);
FORCEPROP 0 LAST $SEC 1
J 0
(-5850 3025);
DISPLAY 0.680851 (-5850 3025);
PAINT MONO (-5850 3025);
DISPLAY INVISIBLE (-5850 3025);
FORCEPROP 0 LAST CDS_SEC 1
J 0
(-5850 3025);
DISPLAY 1.021277 (-5850 3025);
DISPLAY INVISIBLE (-5850 3025);
FORCEADD Q_RES..1
(-5450 2375);
FORCEPROP 1 LAST PART_NUMBER CS-3302FB01
J 0
(-5650 2250);
DISPLAY 0.617021 (-5650 2250);
PAINT BLUE (-5650 2250);
DISPLAY INVISIBLE (-5650 2250);
FORCEPROP 1 LAST MATERIAL CHIP
J 0
(-5450 2300);
DISPLAY 0.617021 (-5450 2300);
PAINT SKYBLUE (-5450 2300);
FORCEPROP 1 LAST WATTAGE 1/16W
J 2
(-5500 2350);
DISPLAY 0.617021 (-5500 2350);
PAINT SKYBLUE (-5500 2350);
FORCEPROP 1 LAST PACK_TYPE 0402LF
J 0
(-5650 2300);
DISPLAY 0.617021 (-5650 2300);
PAINT SKYBLUE (-5650 2300);
FORCEPROP 1 LAST TOLERANCE 1%
J 0
(-5250 2375);
DISPLAY 0.617021 (-5250 2375);
PAINT SKYBLUE (-5250 2375);
FORCEPROP 1 LAST VALUE 3.3
J 2
(-5275 2375);
DISPLAY 0.617021 (-5275 2375);
PAINT SKYBLUE (-5275 2375);
FORCEPROP 1 LAST LOCATION PR1784
J 0
(-5675 2375);
DISPLAY 0.617021 (-5675 2375);
PAINT AQUA (-5675 2375);
FORCEPROP 1 LASTPIN (-5550 2375) $PN 1
J 0
(-5538 2387);
DISPLAY 0.617021 (-5538 2387);
FORCEPROP 1 LASTPIN (-5350 2375) $PN 2
J 0
(-5388 2387);
DISPLAY 0.617021 (-5388 2387);
FORCEPROP 2 LAST CDS_LIB pure_quanta
J 0
(-5450 2375);
PAINT MONO (-5450 2375);
DISPLAY INVISIBLE (-5450 2375);
FORCEPROP 1 LAST PATH I19
J 0
(-5500 2525);
DISPLAY 0.978723 (-5500 2525);
PAINT WHITE (-5500 2525);
DISPLAY INVISIBLE (-5500 2525);
FORCEPROP 2 LAST $SEC 1
J 0
(-5500 2575);
DISPLAY 0.680851 (-5500 2575);
PAINT MONO (-5500 2575);
DISPLAY INVISIBLE (-5500 2575);
FORCEPROP 2 LAST CDS_SEC 1
J 0
(-5500 2575);
DISPLAY 1.021277 (-5500 2575);
DISPLAY INVISIBLE (-5500 2575);
FORCEADD UNIVERSAL_GND..1
(-8775 1100);
FORCEPROP 3 LASTPIN (-8775 1150) SIG_NAME GND\g
J 0
(-8765 1160);
DISPLAY 0.659574 (-8765 1160);
PAINT MONO (-8765 1160);
DISPLAY INVISIBLE (-8765 1160);
FORCEPROP 1 LAST HDL_POWER GND
J 1
(-8750 1025);
DISPLAY 0.872340 (-8750 1025);
PAINT GREEN (-8750 1025);
DISPLAY INVISIBLE (-8750 1025);
FORCEPROP 2 LAST CDS_LIB logical_power
J 0
(-8775 1100);
DISPLAY INVISIBLE (-8775 1100);
FORCEPROP 1 LAST PATH I2
J 0
(-8700 1100);
DISPLAY 0.872340 (-8700 1100);
PAINT AQUA (-8700 1100);
DISPLAY INVISIBLE (-8700 1100);
FORCEADD Q_CAP..1
(-5500 2825);
FORCEPROP 1 LAST PART_NUMBER CH5103KEB01
J 0
(-5450 2675);
DISPLAY 0.617021 (-5450 2675);
PAINT BLUE (-5450 2675);
DISPLAY INVISIBLE (-5450 2675);
FORCEPROP 1 LAST MATERIAL X6S
J 0
(-5450 2775);
DISPLAY 0.617021 (-5450 2775);
PAINT SKYBLUE (-5450 2775);
FORCEPROP 1 LAST PACK_TYPE C0402
J 0
(-5450 2725);
DISPLAY 0.617021 (-5450 2725);
PAINT SKYBLUE (-5450 2725);
FORCEPROP 1 LAST VOLTAGE 16V
J 0
(-5450 2875);
DISPLAY 0.617021 (-5450 2875);
PAINT SKYBLUE (-5450 2875);
FORCEPROP 1 LAST VALUE 1UF
J 0
(-5450 2925);
DISPLAY 0.617021 (-5450 2925);
PAINT SKYBLUE (-5450 2925);
FORCEPROP 1 LAST TOLERANCE 10%
J 0
(-5450 2825);
DISPLAY 0.617021 (-5450 2825);
PAINT SKYBLUE (-5450 2825);
FORCEPROP 1 LAST LOCATION PC635
J 0
(-5450 2975);
DISPLAY 0.617021 (-5450 2975);
PAINT AQUA (-5450 2975);
FORCEPROP 1 LASTPIN (-5500 2925) $PN 1
J 0
(-5490 2905);
DISPLAY 0.617021 (-5490 2905);
PAINT MONO (-5490 2905);
FORCEPROP 1 LASTPIN (-5500 2725) $PN 2
J 0
(-5490 2705);
DISPLAY 0.617021 (-5490 2705);
PAINT MONO (-5490 2705);
FORCEPROP 2 LAST CDS_LIB pure_quanta
J 0
(-5500 2825);
DISPLAY INVISIBLE (-5500 2825);
FORCEPROP 1 LAST PATH I20
J 0
(-5450 2975);
DISPLAY 0.978723 (-5450 2975);
PAINT WHITE (-5450 2975);
DISPLAY INVISIBLE (-5450 2975);
FORCEPROP 1 LAST LOCATION PC635
J 0
(-5450 3025);
DISPLAY 1.021277 (-5450 3025);
PAINT AQUA (-5450 3025);
DISPLAY INVISIBLE (-5450 3025);
FORCEPROP 0 LAST $SEC 1
J 0
(-5450 3025);
DISPLAY 0.680851 (-5450 3025);
PAINT MONO (-5450 3025);
DISPLAY INVISIBLE (-5450 3025);
FORCEPROP 0 LAST CDS_SEC 1
J 0
(-5450 3025);
DISPLAY 1.021277 (-5450 3025);
DISPLAY INVISIBLE (-5450 3025);
FORCEADD Q_CAP..1
(-5100 2825);
FORCEPROP 1 LAST PART_NUMBER CH6223MEA01
J 0
(-5050 2675);
DISPLAY 0.617021 (-5050 2675);
PAINT BLUE (-5050 2675);
DISPLAY INVISIBLE (-5050 2675);
FORCEPROP 1 LAST TOLERANCE 20%
J 0
(-5050 2825);
DISPLAY 0.617021 (-5050 2825);
PAINT SKYBLUE (-5050 2825);
FORCEPROP 1 LAST PACK_TYPE C0805
J 0
(-5050 2725);
DISPLAY 0.617021 (-5050 2725);
PAINT SKYBLUE (-5050 2725);
FORCEPROP 1 LAST VOLTAGE 16V
J 0
(-5050 2875);
DISPLAY 0.617021 (-5050 2875);
PAINT SKYBLUE (-5050 2875);
FORCEPROP 1 LAST VALUE 22UF
J 0
(-5050 2925);
DISPLAY 0.617021 (-5050 2925);
PAINT SKYBLUE (-5050 2925);
FORCEPROP 1 LAST MATERIAL X6S
J 0
(-5050 2775);
DISPLAY 0.617021 (-5050 2775);
PAINT SKYBLUE (-5050 2775);
FORCEPROP 1 LAST LOCATION PC637
J 0
(-5050 2975);
DISPLAY 0.617021 (-5050 2975);
PAINT AQUA (-5050 2975);
FORCEPROP 1 LASTPIN (-5100 2925) $PN 1
J 0
(-5090 2905);
DISPLAY 0.617021 (-5090 2905);
PAINT MONO (-5090 2905);
FORCEPROP 1 LASTPIN (-5100 2725) $PN 2
J 0
(-5090 2705);
DISPLAY 0.617021 (-5090 2705);
PAINT MONO (-5090 2705);
FORCEPROP 2 LAST CDS_LIB pure_quanta
J 0
(-5100 2825);
DISPLAY INVISIBLE (-5100 2825);
FORCEPROP 1 LAST PATH I21
J 0
(-5050 2975);
DISPLAY 0.978723 (-5050 2975);
PAINT WHITE (-5050 2975);
DISPLAY INVISIBLE (-5050 2975);
FORCEPROP 1 LAST LOCATION PC637
J 0
(-5050 3025);
DISPLAY 1.021277 (-5050 3025);
PAINT AQUA (-5050 3025);
DISPLAY INVISIBLE (-5050 3025);
FORCEPROP 0 LAST $SEC 1
J 0
(-5050 3025);
DISPLAY 0.680851 (-5050 3025);
PAINT MONO (-5050 3025);
DISPLAY INVISIBLE (-5050 3025);
FORCEPROP 0 LAST CDS_SEC 1
J 0
(-5050 3025);
DISPLAY 1.021277 (-5050 3025);
DISPLAY INVISIBLE (-5050 3025);
FORCEADD Q_CAP..1
R 2
(-4675 2200);
FORCEPROP 1 LAST PART_NUMBER CH4106K1B01
J 2
(-4725 2125);
DISPLAY 0.617021 (-4725 2125);
PAINT BLUE (-4725 2125);
DISPLAY INVISIBLE (-4725 2125);
FORCEPROP 1 LAST VALUE 100NF
J 2
(-4725 2225);
DISPLAY 0.617021 (-4725 2225);
PAINT SKYBLUE (-4725 2225);
FORCEPROP 1 LAST MATERIAL X7R
J 2
(-4725 2150);
DISPLAY 0.617021 (-4725 2150);
PAINT SKYBLUE (-4725 2150);
FORCEPROP 1 LAST PACK_TYPE C0402
J 2
(-4725 2100);
DISPLAY 0.617021 (-4725 2100);
PAINT SKYBLUE (-4725 2100);
FORCEPROP 1 LAST VOLTAGE 50V
J 2
(-4725 2200);
DISPLAY 0.617021 (-4725 2200);
PAINT SKYBLUE (-4725 2200);
FORCEPROP 1 LAST TOLERANCE 10%
J 2
(-4725 2175);
DISPLAY 0.617021 (-4725 2175);
PAINT SKYBLUE (-4725 2175);
FORCEPROP 1 LAST LOCATION PC636
J 2
(-4725 2275);
DISPLAY 0.617021 (-4725 2275);
PAINT AQUA (-4725 2275);
FORCEPROP 1 LASTPIN (-4675 2300) $PN 1
J 2
(-4685 2280);
DISPLAY 0.617021 (-4685 2280);
FORCEPROP 1 LASTPIN (-4675 2100) $PN 2
J 2
(-4685 2080);
DISPLAY 0.617021 (-4685 2080);
FORCEPROP 2 LAST CDS_LIB pure_quanta
J 2
(-4675 2200);
PAINT MONO (-4675 2200);
DISPLAY INVISIBLE (-4675 2200);
FORCEPROP 1 LAST PATH I22
J 2
(-4725 2350);
DISPLAY 0.978723 (-4725 2350);
PAINT WHITE (-4725 2350);
DISPLAY INVISIBLE (-4725 2350);
FORCEPROP 2 LAST $SEC 1
J 0
(-4725 2400);
DISPLAY 0.680851 (-4725 2400);
PAINT MONO (-4725 2400);
DISPLAY INVISIBLE (-4725 2400);
FORCEPROP 2 LAST CDS_SEC 1
J 0
(-4725 2400);
DISPLAY 1.021277 (-4725 2400);
DISPLAY INVISIBLE (-4725 2400);
FORCEADD Q_CAP..1
(-4700 2825);
FORCEPROP 1 LAST PART_NUMBER CH6223MEA01
J 0
(-4650 2675);
DISPLAY 0.617021 (-4650 2675);
PAINT BLUE (-4650 2675);
DISPLAY INVISIBLE (-4650 2675);
FORCEPROP 1 LAST TOLERANCE 20%
J 0
(-4650 2825);
DISPLAY 0.617021 (-4650 2825);
PAINT SKYBLUE (-4650 2825);
FORCEPROP 1 LAST MATERIAL X6S
J 0
(-4650 2775);
DISPLAY 0.617021 (-4650 2775);
PAINT SKYBLUE (-4650 2775);
FORCEPROP 1 LAST PACK_TYPE C0805
J 0
(-4650 2725);
DISPLAY 0.617021 (-4650 2725);
PAINT SKYBLUE (-4650 2725);
FORCEPROP 1 LAST VALUE 22UF
J 0
(-4650 2925);
DISPLAY 0.617021 (-4650 2925);
PAINT SKYBLUE (-4650 2925);
FORCEPROP 1 LAST VOLTAGE 16V
J 0
(-4650 2875);
DISPLAY 0.617021 (-4650 2875);
PAINT SKYBLUE (-4650 2875);
FORCEPROP 1 LAST LOCATION PC638
J 0
(-4650 2975);
DISPLAY 0.617021 (-4650 2975);
PAINT AQUA (-4650 2975);
FORCEPROP 1 LASTPIN (-4700 2925) $PN 1
J 0
(-4690 2905);
DISPLAY 0.617021 (-4690 2905);
PAINT MONO (-4690 2905);
FORCEPROP 1 LASTPIN (-4700 2725) $PN 2
J 0
(-4690 2705);
DISPLAY 0.617021 (-4690 2705);
PAINT MONO (-4690 2705);
FORCEPROP 2 LAST CDS_LIB pure_quanta
J 0
(-4700 2825);
DISPLAY INVISIBLE (-4700 2825);
FORCEPROP 1 LAST PATH I23
J 0
(-4650 2975);
DISPLAY 0.978723 (-4650 2975);
PAINT WHITE (-4650 2975);
DISPLAY INVISIBLE (-4650 2975);
FORCEPROP 1 LAST LOCATION PC638
J 0
(-4650 3025);
DISPLAY 1.021277 (-4650 3025);
PAINT AQUA (-4650 3025);
DISPLAY INVISIBLE (-4650 3025);
FORCEPROP 0 LAST $SEC 1
J 0
(-4650 3025);
DISPLAY 0.680851 (-4650 3025);
PAINT MONO (-4650 3025);
DISPLAY INVISIBLE (-4650 3025);
FORCEPROP 0 LAST CDS_SEC 1
J 0
(-4650 3025);
DISPLAY 1.021277 (-4650 3025);
DISPLAY INVISIBLE (-4650 3025);
FORCEADD Q_CAP..1
(-3750 1725);
FORCEPROP 1 LAST PART_NUMBER CH4106K1B01
J 0
(-3700 1550);
DISPLAY 0.617021 (-3700 1550);
PAINT BLUE (-3700 1550);
DISPLAY INVISIBLE (-3700 1550);
FORCEPROP 1 LAST TOLERANCE 10%
J 0
(-3700 1700);
DISPLAY 0.617021 (-3700 1700);
PAINT SKYBLUE (-3700 1700);
FORCEPROP 1 LAST VOLTAGE 50V
J 0
(-3700 1750);
DISPLAY 0.617021 (-3700 1750);
PAINT SKYBLUE (-3700 1750);
FORCEPROP 1 LAST VALUE 100NF
J 0
(-3700 1800);
DISPLAY 0.617021 (-3700 1800);
PAINT SKYBLUE (-3700 1800);
FORCEPROP 1 LAST PACK_TYPE C0402
J 0
(-3700 1600);
DISPLAY 0.617021 (-3700 1600);
PAINT SKYBLUE (-3700 1600);
FORCEPROP 1 LAST MATERIAL X7R
J 0
(-3700 1650);
DISPLAY 0.617021 (-3700 1650);
PAINT SKYBLUE (-3700 1650);
FORCEPROP 1 LAST LOCATION PC639
J 0
(-3700 1850);
DISPLAY 0.617021 (-3700 1850);
PAINT AQUA (-3700 1850);
FORCEPROP 1 LASTPIN (-3750 1825) $PN 1
J 0
(-3740 1805);
DISPLAY 0.617021 (-3740 1805);
PAINT MONO (-3740 1805);
FORCEPROP 1 LASTPIN (-3750 1625) $PN 2
J 0
(-3740 1605);
DISPLAY 0.617021 (-3740 1605);
PAINT MONO (-3740 1605);
FORCEPROP 2 LAST CDS_LIB pure_quanta
J 0
(-3750 1725);
DISPLAY INVISIBLE (-3750 1725);
FORCEPROP 1 LAST PATH I24
J 0
(-3700 1875);
DISPLAY 0.978723 (-3700 1875);
PAINT WHITE (-3700 1875);
DISPLAY INVISIBLE (-3700 1875);
FORCEPROP 1 LAST LOCATION PC639
J 0
(-3700 1900);
DISPLAY 1.021277 (-3700 1900);
PAINT AQUA (-3700 1900);
DISPLAY INVISIBLE (-3700 1900);
FORCEPROP 0 LAST $SEC 1
J 0
(-3700 1900);
DISPLAY 0.680851 (-3700 1900);
PAINT MONO (-3700 1900);
DISPLAY INVISIBLE (-3700 1900);
FORCEPROP 0 LAST CDS_SEC 1
J 0
(-3700 1900);
DISPLAY 1.021277 (-3700 1900);
DISPLAY INVISIBLE (-3700 1900);
FORCEADD Q_CAP..1
(-3350 1725);
FORCEPROP 1 LAST PART_NUMBER CH622KMEA03
J 0
(-3300 1550);
DISPLAY 0.617021 (-3300 1550);
PAINT BLUE (-3300 1550);
DISPLAY INVISIBLE (-3300 1550);
FORCEPROP 1 LAST TOLERANCE 20%
J 0
(-3300 1700);
DISPLAY 0.617021 (-3300 1700);
PAINT SKYBLUE (-3300 1700);
FORCEPROP 1 LAST PACK_TYPE C0805
J 0
(-3300 1600);
DISPLAY 0.617021 (-3300 1600);
PAINT SKYBLUE (-3300 1600);
FORCEPROP 1 LAST MATERIAL X6S
J 0
(-3300 1650);
DISPLAY 0.617021 (-3300 1650);
PAINT SKYBLUE (-3300 1650);
FORCEPROP 1 LAST VALUE 22UF
J 0
(-3300 1800);
DISPLAY 0.617021 (-3300 1800);
PAINT SKYBLUE (-3300 1800);
FORCEPROP 1 LAST VOLTAGE 4V
J 0
(-3300 1750);
DISPLAY 0.617021 (-3300 1750);
PAINT SKYBLUE (-3300 1750);
FORCEPROP 1 LAST LOCATION PC641
J 0
(-3300 1850);
DISPLAY 0.617021 (-3300 1850);
PAINT AQUA (-3300 1850);
FORCEPROP 1 LASTPIN (-3350 1825) $PN 1
J 0
(-3340 1805);
DISPLAY 0.617021 (-3340 1805);
PAINT MONO (-3340 1805);
FORCEPROP 1 LASTPIN (-3350 1625) $PN 2
J 0
(-3340 1605);
DISPLAY 0.617021 (-3340 1605);
PAINT MONO (-3340 1605);
FORCEPROP 2 LAST CDS_LIB pure_quanta
J 0
(-3350 1725);
DISPLAY INVISIBLE (-3350 1725);
FORCEPROP 1 LAST PATH I25
J 0
(-3300 1875);
DISPLAY 0.978723 (-3300 1875);
PAINT WHITE (-3300 1875);
DISPLAY INVISIBLE (-3300 1875);
FORCEPROP 1 LAST LOCATION PC641
J 0
(-3300 1900);
DISPLAY 1.021277 (-3300 1900);
PAINT AQUA (-3300 1900);
DISPLAY INVISIBLE (-3300 1900);
FORCEPROP 0 LAST $SEC 1
J 0
(-3300 1900);
DISPLAY 0.680851 (-3300 1900);
PAINT MONO (-3300 1900);
DISPLAY INVISIBLE (-3300 1900);
FORCEPROP 0 LAST CDS_SEC 1
J 0
(-3300 1900);
DISPLAY 1.021277 (-3300 1900);
DISPLAY INVISIBLE (-3300 1900);
FORCEADD Q_CAPP..1
(-3150 300);
FORCEPROP 1 LAST PART_NUMBER CH733RY8807
J 0
(-3100 100);
DISPLAY 0.617021 (-3100 100);
PAINT BLUE (-3100 100);
DISPLAY INVISIBLE (-3100 100);
FORCEPROP 1 LAST PACK_TYPE SMLF
J 0
(-3100 150);
DISPLAY 0.617021 (-3100 150);
PAINT SKYBLUE (-3100 150);
FORCEPROP 1 LAST VOLTAGE 2V
J 0
(-3100 250);
DISPLAY 0.617021 (-3100 250);
PAINT SKYBLUE (-3100 250);
FORCEPROP 1 LAST VALUE 330UF
J 0
(-3100 350);
DISPLAY 0.617021 (-3100 350);
PAINT SKYBLUE (-3100 350);
FORCEPROP 1 LAST TOLERANCE 35%
J 0
(-3100 300);
DISPLAY 0.617021 (-3100 300);
PAINT SKYBLUE (-3100 300);
FORCEPROP 1 LAST MATERIAL SPCAP
J 0
(-3100 200);
DISPLAY 0.617021 (-3100 200);
PAINT SKYBLUE (-3100 200);
FORCEPROP 1 LAST LOCATION PC1910
J 0
(-3100 400);
DISPLAY 0.617021 (-3100 400);
PAINT AQUA (-3100 400);
FORCEPROP 1 LASTPIN (-3150 400) $PN 1
J 0
(-3140 385);
DISPLAY 0.617021 (-3140 385);
FORCEPROP 1 LASTPIN (-3150 200) $PN 2
J 0
(-3140 185);
DISPLAY 0.617021 (-3140 185);
FORCEPROP 2 LAST CDS_LIB pure_quanta
J 0
(-3150 300);
PAINT MONO (-3150 300);
DISPLAY INVISIBLE (-3150 300);
FORCEPROP 1 LAST PATH I26
J 0
(-3100 450);
DISPLAY 0.978723 (-3100 450);
DISPLAY INVISIBLE (-3100 450);
FORCEPROP 2 LAST $SEC 1
J 0
(-3100 500);
DISPLAY 0.680851 (-3100 500);
PAINT MONO (-3100 500);
DISPLAY INVISIBLE (-3100 500);
FORCEPROP 2 LAST CDS_SEC 1
J 0
(-3100 500);
DISPLAY 1.021277 (-3100 500);
DISPLAY INVISIBLE (-3100 500);
FORCEADD Q_CAPP..1
(-2675 275);
FORCEPROP 1 LAST PART_NUMBER CC7560JMD16
J 0
(-2625 100);
DISPLAY 0.617021 (-2625 100);
PAINT BLUE (-2625 100);
DISPLAY INVISIBLE (-2625 100);
FORCEPROP 1 LAST PACK_TYPE THLF
J 0
(-2625 150);
DISPLAY 0.617021 (-2625 150);
PAINT SKYBLUE (-2625 150);
FORCEPROP 1 LAST VALUE 560UF
J 0
(-2625 350);
DISPLAY 0.617021 (-2625 350);
PAINT SKYBLUE (-2625 350);
FORCEPROP 1 LAST TOLERANCE 20%
J 0
(-2625 300);
DISPLAY 0.617021 (-2625 300);
PAINT SKYBLUE (-2625 300);
FORCEPROP 1 LAST MATERIAL OSCON
J 0
(-2625 200);
DISPLAY 0.617021 (-2625 200);
PAINT SKYBLUE (-2625 200);
FORCEPROP 1 LAST VOLTAGE 2.5V
J 0
(-2625 250);
DISPLAY 0.617021 (-2625 250);
PAINT SKYBLUE (-2625 250);
FORCEPROP 1 LAST LOCATION PC1644
J 0
(-2625 400);
DISPLAY 0.617021 (-2625 400);
PAINT AQUA (-2625 400);
FORCEPROP 2 LAST CDS_LIB pure_quanta
J 0
(-2675 275);
PAINT MONO (-2675 275);
DISPLAY INVISIBLE (-2675 275);
FORCEPROP 1 LAST PATH I27
J 0
(-2625 425);
DISPLAY 0.978723 (-2625 425);
DISPLAY INVISIBLE (-2625 425);
FORCEPROP 2 LAST $SEC 1
J 0
(-2625 475);
DISPLAY 0.680851 (-2625 475);
PAINT MONO (-2625 475);
DISPLAY INVISIBLE (-2625 475);
FORCEPROP 0 LAST CDS_SEC 1
J 0
(-2625 475);
DISPLAY 1.021277 (-2625 475);
DISPLAY INVISIBLE (-2625 475);
FORCEPROP 1 LASTPIN (-2675 375) $PN 1
J 0
(-2665 360);
DISPLAY 0.787234 (-2665 360);
DISPLAY INVISIBLE (-2665 360);
FORCEPROP 1 LASTPIN (-2675 175) $PN 2
J 0
(-2665 160);
DISPLAY 0.787234 (-2665 160);
DISPLAY INVISIBLE (-2665 160);
FORCEADD Q_CAP..1
(-2825 1725);
FORCEPROP 1 LAST PART_NUMBER CH622KMEA03
J 0
(-2775 1550);
DISPLAY 0.617021 (-2775 1550);
PAINT BLUE (-2775 1550);
DISPLAY INVISIBLE (-2775 1550);
FORCEPROP 1 LAST TOLERANCE 20%
J 0
(-2775 1700);
DISPLAY 0.617021 (-2775 1700);
PAINT SKYBLUE (-2775 1700);
FORCEPROP 1 LAST VOLTAGE 4V
J 0
(-2775 1750);
DISPLAY 0.617021 (-2775 1750);
PAINT SKYBLUE (-2775 1750);
FORCEPROP 1 LAST VALUE 22UF
J 0
(-2775 1800);
DISPLAY 0.617021 (-2775 1800);
PAINT SKYBLUE (-2775 1800);
FORCEPROP 1 LAST PACK_TYPE C0805
J 0
(-2775 1600);
DISPLAY 0.617021 (-2775 1600);
PAINT SKYBLUE (-2775 1600);
FORCEPROP 1 LAST MATERIAL X6S
J 0
(-2775 1650);
DISPLAY 0.617021 (-2775 1650);
PAINT SKYBLUE (-2775 1650);
FORCEPROP 1 LAST LOCATION PC642
J 0
(-2775 1850);
DISPLAY 0.617021 (-2775 1850);
PAINT AQUA (-2775 1850);
FORCEPROP 1 LASTPIN (-2825 1825) $PN 1
J 0
(-2815 1805);
DISPLAY 0.617021 (-2815 1805);
PAINT MONO (-2815 1805);
FORCEPROP 1 LASTPIN (-2825 1625) $PN 2
J 0
(-2815 1605);
DISPLAY 0.617021 (-2815 1605);
PAINT MONO (-2815 1605);
FORCEPROP 2 LAST CDS_LIB pure_quanta
J 0
(-2825 1725);
DISPLAY INVISIBLE (-2825 1725);
FORCEPROP 1 LAST PATH I28
J 0
(-2775 1875);
DISPLAY 0.978723 (-2775 1875);
PAINT WHITE (-2775 1875);
DISPLAY INVISIBLE (-2775 1875);
FORCEPROP 1 LAST LOCATION PC642
J 0
(-2775 1900);
DISPLAY 1.021277 (-2775 1900);
PAINT AQUA (-2775 1900);
DISPLAY INVISIBLE (-2775 1900);
FORCEPROP 0 LAST $SEC 1
J 0
(-2775 1900);
DISPLAY 0.680851 (-2775 1900);
PAINT MONO (-2775 1900);
DISPLAY INVISIBLE (-2775 1900);
FORCEPROP 0 LAST CDS_SEC 1
J 0
(-2775 1900);
DISPLAY 1.021277 (-2775 1900);
DISPLAY INVISIBLE (-2775 1900);
FORCEADD Q_CAP..1
(-2275 1725);
FORCEPROP 1 LAST PART_NUMBER CH622KMEA03
J 0
(-2225 1550);
DISPLAY 0.617021 (-2225 1550);
PAINT BLUE (-2225 1550);
DISPLAY INVISIBLE (-2225 1550);
FORCEPROP 1 LAST TOLERANCE 20%
J 0
(-2225 1700);
DISPLAY 0.617021 (-2225 1700);
PAINT SKYBLUE (-2225 1700);
FORCEPROP 1 LAST VOLTAGE 4V
J 0
(-2225 1750);
DISPLAY 0.617021 (-2225 1750);
PAINT SKYBLUE (-2225 1750);
FORCEPROP 1 LAST PACK_TYPE C0805
J 0
(-2225 1600);
DISPLAY 0.617021 (-2225 1600);
PAINT SKYBLUE (-2225 1600);
FORCEPROP 1 LAST VALUE 22UF
J 0
(-2225 1800);
DISPLAY 0.617021 (-2225 1800);
PAINT SKYBLUE (-2225 1800);
FORCEPROP 1 LAST MATERIAL X6S
J 0
(-2225 1650);
DISPLAY 0.617021 (-2225 1650);
PAINT SKYBLUE (-2225 1650);
FORCEPROP 1 LAST LOCATION PC1
J 0
(-2225 1850);
DISPLAY 0.617021 (-2225 1850);
PAINT AQUA (-2225 1850);
FORCEPROP 1 LASTPIN (-2275 1825) $PN 1
J 0
(-2265 1805);
DISPLAY 0.617021 (-2265 1805);
PAINT MONO (-2265 1805);
FORCEPROP 1 LASTPIN (-2275 1625) $PN 2
J 0
(-2265 1605);
DISPLAY 0.617021 (-2265 1605);
PAINT MONO (-2265 1605);
FORCEPROP 2 LAST CDS_LIB pure_quanta
J 0
(-2275 1725);
DISPLAY INVISIBLE (-2275 1725);
FORCEPROP 1 LAST PATH I29
J 0
(-2225 1875);
DISPLAY 0.978723 (-2225 1875);
PAINT WHITE (-2225 1875);
DISPLAY INVISIBLE (-2225 1875);
FORCEPROP 1 LAST LOCATION PC1
J 0
(-2225 1900);
DISPLAY 1.021277 (-2225 1900);
PAINT AQUA (-2225 1900);
DISPLAY INVISIBLE (-2225 1900);
FORCEPROP 0 LAST $SEC 1
J 0
(-2225 1900);
DISPLAY 0.680851 (-2225 1900);
PAINT MONO (-2225 1900);
DISPLAY INVISIBLE (-2225 1900);
FORCEPROP 0 LAST CDS_SEC 1
J 0
(-2225 1900);
DISPLAY 1.021277 (-2225 1900);
DISPLAY INVISIBLE (-2225 1900);
FORCEADD Q_RES..2
R 2
(-8775 1325);
FORCEPROP 1 LAST PART_NUMBER CS28872FB01
J 2
(-8815 1200);
DISPLAY 0.617021 (-8815 1200);
PAINT BLUE (-8815 1200);
DISPLAY INVISIBLE (-8815 1200);
FORCEPROP 1 LAST TOLERANCE 1%
J 2
(-8820 1350);
DISPLAY 0.617021 (-8820 1350);
PAINT SKYBLUE (-8820 1350);
FORCEPROP 1 LAST WATTAGE 1/16W
J 2
(-8815 1300);
DISPLAY 0.617021 (-8815 1300);
PAINT SKYBLUE (-8815 1300);
FORCEPROP 1 LAST MATERIAL EMPTY
J 2
(-8815 1250);
DISPLAY 0.617021 (-8815 1250);
PAINT RED (-8815 1250);
FORCEPROP 1 LAST PACK_TYPE 0402LF
J 2
(-8815 1150);
DISPLAY 0.617021 (-8815 1150);
PAINT SKYBLUE (-8815 1150);
FORCEPROP 1 LAST VALUE 8.87K
J 2
(-8820 1400);
DISPLAY 0.617021 (-8820 1400);
PAINT SKYBLUE (-8820 1400);
FORCEPROP 1 LAST LOCATION PR2718
J 2
(-8820 1450);
DISPLAY 0.617021 (-8820 1450);
PAINT AQUA (-8820 1450);
FORCEPROP 1 LASTPIN (-8775 1425) $PN 1
J 2
(-8780 1387);
DISPLAY 0.617021 (-8780 1387);
PAINT MONO (-8780 1387);
FORCEPROP 1 LASTPIN (-8775 1225) $PN 2
J 2
(-8780 1235);
DISPLAY 0.617021 (-8780 1235);
PAINT MONO (-8780 1235);
FORCEPROP 2 LAST CDS_LIB pure_quanta
J 2
(-8775 1325);
DISPLAY INVISIBLE (-8775 1325);
FORCEPROP 1 LAST PATH I3
J 2
(-8825 1500);
DISPLAY 0.978723 (-8825 1500);
PAINT WHITE (-8825 1500);
DISPLAY INVISIBLE (-8825 1500);
FORCEPROP 0 LAST $SEC 1
J 0
(-8800 1475);
DISPLAY 0.680851 (-8800 1475);
PAINT MONO (-8800 1475);
DISPLAY INVISIBLE (-8800 1475);
FORCEPROP 0 LAST CDS_SEC 1
J 0
(-8800 1475);
DISPLAY 1.021277 (-8800 1475);
DISPLAY INVISIBLE (-8800 1475);
FORCEADD Q_INDUCTOR..1
(-4200 1950);
FORCEPROP 1 LAST PART_NUMBER CV+12^0EZ03
J 0
(-4325 2060);
DISPLAY 0.617021 (-4325 2060);
PAINT BLUE (-4325 2060);
DISPLAY INVISIBLE (-4325 2060);
FORCEPROP 2 LAST VALUE 120NH/69A
J 0
(-4325 2200);
DISPLAY 0.617021 (-4325 2200);
PAINT SKYBLUE (-4325 2200);
FORCEPROP 1 LAST MATERIAL IND
J 0
(-4325 2005);
DISPLAY 0.617021 (-4325 2005);
PAINT SKYBLUE (-4325 2005);
FORCEPROP 2 LAST PACK_TYPE SMLF
J 0
(-4325 2150);
DISPLAY 0.617021 (-4325 2150);
PAINT SKYBLUE (-4325 2150);
FORCEPROP 1 LAST LOCATION PL35
J 0
(-4325 2110);
DISPLAY 0.617021 (-4325 2110);
PAINT AQUA (-4325 2110);
FORCEPROP 0 LASTPIN (-4300 1925) $PN 1
J 2
(-4310 1935);
DISPLAY 0.617021 (-4310 1935);
PAINT MONO (-4310 1935);
FORCEPROP 0 LASTPIN (-4100 1925) $PN 2
J 0
(-4090 1935);
DISPLAY 0.617021 (-4090 1935);
PAINT MONO (-4090 1935);
FORCEPROP 2 LAST CDS_LIB pure_quanta
J 0
(-4200 1950);
DISPLAY INVISIBLE (-4200 1950);
FORCEPROP 1 LAST NEEDS_NO_SIZE TRUE
J 0
(-4200 1950);
DISPLAY 0.468085 (-4200 1950);
PAINT GREEN (-4200 1950);
DISPLAY INVISIBLE (-4200 1950);
FORCEPROP 1 LAST PATH I30
J 0
(-4125 2005);
DISPLAY 0.723404 (-4125 2005);
PAINT GREEN (-4125 2005);
DISPLAY INVISIBLE (-4125 2005);
FORCEPROP 0 LAST $SEC 1
J 0
(-4325 2250);
DISPLAY 0.680851 (-4325 2250);
PAINT MONO (-4325 2250);
DISPLAY INVISIBLE (-4325 2250);
FORCEPROP 0 LAST CDS_SEC 1
J 0
(-4325 2250);
DISPLAY 1.021277 (-4325 2250);
DISPLAY INVISIBLE (-4325 2250);
FORCEADD UNIVERSAL_GND..1
(-4100 2400);
FORCEPROP 3 LASTPIN (-4100 2450) SIG_NAME GND\g
J 0
(-4090 2460);
DISPLAY 0.659574 (-4090 2460);
PAINT MONO (-4090 2460);
DISPLAY INVISIBLE (-4090 2460);
FORCEPROP 1 LAST HDL_POWER GND
J 1
(-4075 2325);
DISPLAY 0.872340 (-4075 2325);
PAINT GREEN (-4075 2325);
DISPLAY INVISIBLE (-4075 2325);
FORCEPROP 2 LAST CDS_LIB logical_power
J 0
(-4100 2400);
PAINT MONO (-4100 2400);
DISPLAY INVISIBLE (-4100 2400);
FORCEPROP 1 LAST PATH I31
J 0
(-4025 2400);
DISPLAY 0.872340 (-4025 2400);
PAINT AQUA (-4025 2400);
DISPLAY INVISIBLE (-4025 2400);
FORCEADD VCC15..1
(-4100 3200);
FORCEPROP 3 LASTPIN (-4100 3150) SIG_NAME SW_P12V_PVCCINFAON_CPU0_FLT\g
J 0
(-4090 3160);
DISPLAY 0.659574 (-4090 3160);
PAINT MONO (-4090 3160);
DISPLAY INVISIBLE (-4090 3160);
FORCEPROP 1 LAST HDL_POWER SW_P12V_PVCCINFAON_CPU0_FLT
J 1
(-4050 3250);
DISPLAY 0.617021 (-4050 3250);
PAINT GREEN (-4050 3250);
FORCEPROP 2 LAST CDS_LIB logical_power
J 0
(-4100 3200);
PAINT MONO (-4100 3200);
DISPLAY INVISIBLE (-4100 3200);
FORCEPROP 1 LAST PATH I32
J 0
(-4050 3225);
DISPLAY 0.872340 (-4050 3225);
PAINT AQUA (-4050 3225);
DISPLAY INVISIBLE (-4050 3225);
FORCEADD UNIVERSAL_GND..1
(-2175 -50);
FORCEPROP 3 LASTPIN (-2175 0) SIG_NAME GND\g
J 0
(-2165 10);
DISPLAY 0.659574 (-2165 10);
PAINT MONO (-2165 10);
DISPLAY INVISIBLE (-2165 10);
FORCEPROP 1 LAST HDL_POWER GND
J 1
(-2150 -125);
DISPLAY 0.872340 (-2150 -125);
PAINT GREEN (-2150 -125);
DISPLAY INVISIBLE (-2150 -125);
FORCEPROP 2 LAST CDS_LIB logical_power
J 0
(-2175 -50);
PAINT MONO (-2175 -50);
DISPLAY INVISIBLE (-2175 -50);
FORCEPROP 1 LAST PATH I33
J 0
(-2100 -50);
DISPLAY 0.872340 (-2100 -50);
PAINT AQUA (-2100 -50);
DISPLAY INVISIBLE (-2100 -50);
FORCEADD Q_CAPP..1
(-2175 275);
FORCEPROP 1 LAST PART_NUMBER CC7560JMD16
J 0
(-2125 100);
DISPLAY 0.617021 (-2125 100);
PAINT BLUE (-2125 100);
DISPLAY INVISIBLE (-2125 100);
FORCEPROP 1 LAST PACK_TYPE THLF
J 0
(-2125 150);
DISPLAY 0.617021 (-2125 150);
PAINT SKYBLUE (-2125 150);
FORCEPROP 1 LAST VALUE 560UF
J 0
(-2125 350);
DISPLAY 0.617021 (-2125 350);
PAINT SKYBLUE (-2125 350);
FORCEPROP 1 LAST TOLERANCE 20%
J 0
(-2125 300);
DISPLAY 0.617021 (-2125 300);
PAINT SKYBLUE (-2125 300);
FORCEPROP 1 LAST MATERIAL OSCON
J 0
(-2125 200);
DISPLAY 0.617021 (-2125 200);
PAINT SKYBLUE (-2125 200);
FORCEPROP 1 LAST VOLTAGE 2.5V
J 0
(-2125 250);
DISPLAY 0.617021 (-2125 250);
PAINT SKYBLUE (-2125 250);
FORCEPROP 1 LAST LOCATION PC1645
J 0
(-2125 400);
DISPLAY 0.617021 (-2125 400);
PAINT AQUA (-2125 400);
FORCEPROP 2 LAST CDS_LIB pure_quanta
J 0
(-2175 275);
PAINT MONO (-2175 275);
DISPLAY INVISIBLE (-2175 275);
FORCEPROP 1 LAST PATH I34
J 0
(-2125 425);
DISPLAY 0.978723 (-2125 425);
DISPLAY INVISIBLE (-2125 425);
FORCEPROP 2 LAST $SEC 1
J 0
(-2125 475);
DISPLAY 0.680851 (-2125 475);
PAINT MONO (-2125 475);
DISPLAY INVISIBLE (-2125 475);
FORCEPROP 0 LAST CDS_SEC 1
J 0
(-2125 475);
DISPLAY 1.021277 (-2125 475);
DISPLAY INVISIBLE (-2125 475);
FORCEPROP 1 LASTPIN (-2175 375) $PN 1
J 0
(-2165 360);
DISPLAY 0.787234 (-2165 360);
DISPLAY INVISIBLE (-2165 360);
FORCEPROP 1 LASTPIN (-2175 175) $PN 2
J 0
(-2165 160);
DISPLAY 0.787234 (-2165 160);
DISPLAY INVISIBLE (-2165 160);
FORCEADD VCC15..1
(-2175 600);
FORCEPROP 3 LASTPIN (-2175 550) SIG_NAME PVCCD_HV_CPU0\g
J 0
(-2165 560);
DISPLAY 0.659574 (-2165 560);
PAINT MONO (-2165 560);
DISPLAY INVISIBLE (-2165 560);
FORCEPROP 1 LAST HDL_POWER PVCCD_HV_CPU0
J 1
(-2175 650);
DISPLAY 0.617021 (-2175 650);
PAINT GREEN (-2175 650);
FORCEPROP 2 LAST CDS_LIB logical_power
J 0
(-2175 600);
DISPLAY INVISIBLE (-2175 600);
FORCEPROP 1 LAST PATH I35
J 0
(-2125 625);
DISPLAY 0.872340 (-2125 625);
PAINT AQUA (-2125 625);
DISPLAY INVISIBLE (-2125 625);
FORCEADD UNIVERSAL_GND..1
(-1825 1350);
FORCEPROP 3 LASTPIN (-1825 1400) SIG_NAME GND\g
J 0
(-1815 1410);
DISPLAY 0.659574 (-1815 1410);
PAINT MONO (-1815 1410);
DISPLAY INVISIBLE (-1815 1410);
FORCEPROP 1 LAST HDL_POWER GND
J 1
(-1800 1275);
DISPLAY 0.872340 (-1800 1275);
PAINT GREEN (-1800 1275);
DISPLAY INVISIBLE (-1800 1275);
FORCEPROP 2 LAST CDS_LIB logical_power
J 0
(-1825 1350);
PAINT MONO (-1825 1350);
DISPLAY INVISIBLE (-1825 1350);
FORCEPROP 1 LAST PATH I36
J 0
(-1750 1350);
DISPLAY 0.872340 (-1750 1350);
PAINT AQUA (-1750 1350);
DISPLAY INVISIBLE (-1750 1350);
FORCEADD Q_RES..2
(-1825 1725);
FORCEPROP 1 LAST PART_NUMBER CS14992FB06
J 0
(-1785 1600);
DISPLAY 0.617021 (-1785 1600);
PAINT BLUE (-1785 1600);
DISPLAY INVISIBLE (-1785 1600);
FORCEPROP 1 LAST VALUE 499
J 0
(-1780 1800);
DISPLAY 0.617021 (-1780 1800);
PAINT SKYBLUE (-1780 1800);
FORCEPROP 1 LAST TOLERANCE 1%
J 0
(-1780 1750);
DISPLAY 0.617021 (-1780 1750);
PAINT SKYBLUE (-1780 1750);
FORCEPROP 1 LAST MATERIAL CHIP
J 0
(-1785 1650);
DISPLAY 0.617021 (-1785 1650);
PAINT SKYBLUE (-1785 1650);
FORCEPROP 1 LAST PACK_TYPE 0402LF
J 0
(-1785 1550);
DISPLAY 0.617021 (-1785 1550);
PAINT SKYBLUE (-1785 1550);
FORCEPROP 1 LAST WATTAGE 1/16W
J 0
(-1785 1700);
DISPLAY 0.617021 (-1785 1700);
PAINT SKYBLUE (-1785 1700);
FORCEPROP 1 LAST LOCATION PR4237
J 0
(-1780 1850);
DISPLAY 0.617021 (-1780 1850);
PAINT AQUA (-1780 1850);
FORCEPROP 1 LASTPIN (-1825 1825) $PN 1
J 0
(-1820 1787);
DISPLAY 0.787234 (-1820 1787);
PAINT MONO (-1820 1787);
FORCEPROP 1 LASTPIN (-1825 1625) $PN 2
J 0
(-1820 1635);
DISPLAY 0.787234 (-1820 1635);
PAINT MONO (-1820 1635);
FORCEPROP 2 LAST BOM_COST VR_PCH
J 0
(-1775 1900);
DISPLAY 0.680851 (-1775 1900);
DISPLAY INVISIBLE (-1775 1900);
FORCEPROP 2 LAST CDS_LIB pure_quanta
J 0
(-1825 1725);
DISPLAY INVISIBLE (-1825 1725);
FORCEPROP 1 LAST PATH I37
J 0
(-1775 1900);
DISPLAY 0.978723 (-1775 1900);
PAINT WHITE (-1775 1900);
DISPLAY INVISIBLE (-1775 1900);
FORCEPROP 0 LAST $SEC 1
J 0
(-1775 1900);
DISPLAY 0.680851 (-1775 1900);
PAINT MONO (-1775 1900);
DISPLAY INVISIBLE (-1775 1900);
FORCEPROP 0 LAST CDS_SEC 1
J 0
(-1775 1900);
DISPLAY 1.021277 (-1775 1900);
DISPLAY INVISIBLE (-1775 1900);
FORCEADD VCC15..1
(-1825 2075);
FORCEPROP 3 LASTPIN (-1825 2025) SIG_NAME PVCCD_HV_CPU0\g
J 0
(-1815 2035);
DISPLAY 0.659574 (-1815 2035);
PAINT MONO (-1815 2035);
DISPLAY INVISIBLE (-1815 2035);
FORCEPROP 1 LAST HDL_POWER PVCCD_HV_CPU0
J 1
(-1775 2125);
DISPLAY 0.617021 (-1775 2125);
PAINT GREEN (-1775 2125);
FORCEPROP 2 LAST CDS_LIB logical_power
J 0
(-1825 2075);
PAINT MONO (-1825 2075);
DISPLAY INVISIBLE (-1825 2075);
FORCEPROP 1 LAST PATH I38
J 0
(-1775 2100);
DISPLAY 0.872340 (-1775 2100);
PAINT AQUA (-1775 2100);
DISPLAY INVISIBLE (-1775 2100);
FORCEADD OFFPAGE..1
(-8225 1325);
FORCEPROP 2 LAST $XR0 278 
J 0
(-8507 1325);
DISPLAY 0.638298 (-8507 1325);
PAINT MONO (-8507 1325);
FORCEPROP 1 LAST COMMENT_BODY TRUE
J 0
(-8100 1225);
DISPLAY 0.872340 (-8100 1225);
PAINT GREEN (-8100 1225);
DISPLAY INVISIBLE (-8100 1225);
FORCEPROP 1 LAST OFFPAGE TRUE
J 0
(-7900 1200);
DISPLAY 0.872340 (-7900 1200);
PAINT GREEN (-7900 1200);
DISPLAY INVISIBLE (-7900 1200);
FORCEPROP 2 LAST CDS_LIB standard
J 0
(-8225 1325);
DISPLAY INVISIBLE (-8225 1325);
FORCEPROP 2 LAST PATH I4
J 0
(-8500 1375);
DISPLAY 1.021277 (-8500 1375);
DISPLAY INVISIBLE (-8500 1375);
FORCEADD OFFPAGE..5
(-8225 1425);
FORCEPROP 2 LAST $XR0 278 
J 0
(-8480 1425);
DISPLAY 0.638298 (-8480 1425);
PAINT MONO (-8480 1425);
FORCEPROP 1 LAST COMMENT_BODY TRUE
J 0
(-8125 1350);
DISPLAY 0.872340 (-8125 1350);
PAINT GREEN (-8125 1350);
DISPLAY INVISIBLE (-8125 1350);
FORCEPROP 1 LAST OFFPAGE TRUE
J 0
(-7900 1300);
DISPLAY 0.872340 (-7900 1300);
PAINT GREEN (-7900 1300);
DISPLAY INVISIBLE (-7900 1300);
FORCEPROP 2 LAST CDS_LIB standard
J 0
(-8225 1425);
DISPLAY INVISIBLE (-8225 1425);
FORCEPROP 2 LAST PATH I5
J 0
(-8475 1475);
DISPLAY 1.021277 (-8475 1475);
DISPLAY INVISIBLE (-8475 1475);
FORCEADD OFFPAGE..1
(-8225 1825);
FORCEPROP 2 LAST $XR0 278 
J 0
(-8507 1825);
DISPLAY 0.638298 (-8507 1825);
PAINT MONO (-8507 1825);
FORCEPROP 1 LAST COMMENT_BODY TRUE
J 0
(-8100 1725);
DISPLAY 0.872340 (-8100 1725);
PAINT GREEN (-8100 1725);
DISPLAY INVISIBLE (-8100 1725);
FORCEPROP 1 LAST OFFPAGE TRUE
J 0
(-7900 1700);
DISPLAY 0.872340 (-7900 1700);
PAINT GREEN (-7900 1700);
DISPLAY INVISIBLE (-7900 1700);
FORCEPROP 2 LAST CDS_LIB standard
J 0
(-8225 1825);
DISPLAY INVISIBLE (-8225 1825);
FORCEPROP 2 LAST PATH I6
J 0
(-8500 1875);
DISPLAY 1.021277 (-8500 1875);
DISPLAY INVISIBLE (-8500 1875);
FORCEADD Q_CAP..2
(-8050 1750);
FORCEPROP 1 LAST PART_NUMBER CH4104K1B00
J 1
(-7775 1700);
DISPLAY 0.617021 (-7775 1700);
PAINT BLUE (-7775 1700);
DISPLAY INVISIBLE (-7775 1700);
FORCEPROP 1 LAST PACK_TYPE 0402
J 1
(-7850 1750);
DISPLAY 0.617021 (-7850 1750);
PAINT SKYBLUE (-7850 1750);
FORCEPROP 1 LAST VOLTAGE 25V
J 0
(-8175 1700);
DISPLAY 0.617021 (-8175 1700);
PAINT SKYBLUE (-8175 1700);
FORCEPROP 1 LAST VALUE 0.1UF
J 2
(-8175 1700);
DISPLAY 0.617021 (-8175 1700);
PAINT SKYBLUE (-8175 1700);
FORCEPROP 1 LAST TOLERANCE 10%
J 2
(-7550 1750);
DISPLAY 0.617021 (-7550 1750);
PAINT SKYBLUE (-7550 1750);
FORCEPROP 1 LAST MATERIAL X7R
J 0
(-7750 1750);
DISPLAY 0.617021 (-7750 1750);
PAINT SKYBLUE (-7750 1750);
FORCEPROP 1 LAST LOCATION PC1354
J 1
(-8250 1750);
DISPLAY 0.617021 (-8250 1750);
PAINT AQUA (-8250 1750);
FORCEPROP 1 LASTPIN (-8150 1750) $PN 1
J 0
(-8160 1765);
DISPLAY 0.617021 (-8160 1765);
FORCEPROP 1 LASTPIN (-7950 1750) $PN 2
J 0
(-7965 1765);
DISPLAY 0.617021 (-7965 1765);
FORCEPROP 2 LAST CDS_LIB pure_quanta
J 0
(-8050 1750);
PAINT MONO (-8050 1750);
DISPLAY INVISIBLE (-8050 1750);
FORCEPROP 1 LAST PATH I7
J 0
(-8050 1950);
DISPLAY 0.978723 (-8050 1950);
PAINT WHITE (-8050 1950);
DISPLAY INVISIBLE (-8050 1950);
FORCEPROP 2 LAST $SEC 1
J 0
(-8050 2000);
DISPLAY 0.680851 (-8050 2000);
PAINT MONO (-8050 2000);
DISPLAY INVISIBLE (-8050 2000);
FORCEPROP 2 LAST CDS_SEC 1
J 0
(-8050 2000);
DISPLAY 1.021277 (-8050 2000);
DISPLAY INVISIBLE (-8050 2000);
FORCEADD ISL99390FRZTR5935..1
(-6700 1925);
FORCEPROP 1 LAST PART_NUMBER AL099390004
J 0
(-7000 2725);
DISPLAY 0.723404 (-7000 2725);
PAINT GREEN (-7000 2725);
DISPLAY INVISIBLE (-7000 2725);
FORCEPROP 2 LAST PART_TYPE SMLF
J 0
(-7000 2950);
DISPLAY 0.638298 (-7000 2950);
FORCEPROP 2 LAST VALUE ISL99390FRZ-TR5935
J 0
(-7000 2875);
DISPLAY 0.617021 (-7000 2875);
PAINT SKYBLUE (-7000 2875);
FORCEPROP 1 LAST MATERIAL IC
J 0
(-7000 2650);
DISPLAY 0.723404 (-7000 2650);
PAINT GREEN (-7000 2650);
FORCEPROP 1 LAST LOCATION PU36
J 0
(-7000 2800);
DISPLAY 0.723404 (-7000 2800);
PAINT GREEN (-7000 2800);
FORCEPROP 2 LASTPIN (-6300 1475) $PN 2
J 0
(-6290 1485);
DISPLAY 0.680851 (-6290 1485);
PAINT MONO (-6290 1485);
FORCEPROP 2 LASTPIN (-6300 2275) $PN 33
J 0
(-6290 2285);
DISPLAY 0.680851 (-6290 2285);
PAINT MONO (-6290 2285);
FORCEPROP 2 LASTPIN (-7150 1675) $PN 31
J 2
(-7160 1685);
DISPLAY 0.680851 (-7160 1685);
PAINT MONO (-7160 1685);
FORCEPROP 2 LASTPIN (-7150 2075) $PN 35
J 2
(-7160 2085);
DISPLAY 0.680851 (-7160 2085);
PAINT MONO (-7160 2085);
FORCEPROP 2 LASTPIN (-6300 1625) $PN 6
J 0
(-6290 1635);
DISPLAY 0.680851 (-6290 1635);
PAINT MONO (-6290 1635);
FORCEPROP 2 LASTPIN (-6300 1575) $PN 41
J 0
(-6290 1585);
DISPLAY 0.680851 (-6290 1585);
PAINT MONO (-6290 1585);
FORCEPROP 2 LASTPIN (-7150 1925) $PN 38
J 2
(-7160 1935);
DISPLAY 0.680851 (-7160 1935);
PAINT MONO (-7160 1935);
FORCEPROP 2 LASTPIN (-7150 1625) $PN 37
J 2
(-7160 1635);
DISPLAY 0.680851 (-7160 1635);
PAINT MONO (-7160 1635);
FORCEPROP 2 LASTPIN (-6300 1425) $PN 5
J 0
(-6290 1435);
DISPLAY 0.680851 (-6290 1435);
PAINT MONO (-6290 1435);
FORCEPROP 2 LASTPIN (-6300 1375) $PN 7_9-20_24
J 0
(-6290 1385);
DISPLAY 0.680851 (-6290 1385);
PAINT MONO (-6290 1385);
FORCEPROP 2 LASTPIN (-6300 1325) $PN 40
J 0
(-6290 1335);
DISPLAY 0.680851 (-6290 1335);
PAINT MONO (-6290 1335);
FORCEPROP 2 LASTPIN (-6300 2025) $PN 32
J 0
(-6290 2035);
DISPLAY 0.680851 (-6290 2035);
PAINT MONO (-6290 2035);
FORCEPROP 2 LASTPIN (-7150 2575) $PN 4
J 2
(-7160 2585);
DISPLAY 0.680851 (-7160 2585);
PAINT MONO (-7160 2585);
FORCEPROP 2 LASTPIN (-7150 1325) $PN 34
J 2
(-7160 1335);
DISPLAY 0.680851 (-7160 1335);
PAINT MONO (-7160 1335);
FORCEPROP 2 LASTPIN (-7150 1825) $PN 39
J 2
(-7160 1835);
DISPLAY 0.680851 (-7160 1835);
PAINT MONO (-7160 1835);
FORCEPROP 2 LASTPIN (-6300 1925) $PN 10_19
J 0
(-6290 1935);
DISPLAY 0.680851 (-6290 1935);
PAINT MONO (-6290 1935);
FORCEPROP 2 LASTPIN (-7150 1425) $PN 36
J 2
(-7160 1435);
DISPLAY 0.680851 (-7160 1435);
PAINT MONO (-7160 1435);
FORCEPROP 2 LASTPIN (-7150 2275) $PN 3
J 2
(-7160 2285);
DISPLAY 0.680851 (-7160 2285);
PAINT MONO (-7160 2285);
FORCEPROP 2 LASTPIN (-6300 2575) $PN 25_29
J 0
(-6290 2585);
DISPLAY 0.680851 (-6290 2585);
PAINT MONO (-6290 2585);
FORCEPROP 2 LASTPIN (-6300 2525) $PN 30
J 0
(-6290 2535);
DISPLAY 0.680851 (-6290 2535);
PAINT MONO (-6290 2535);
FORCEPROP 2 LASTPIN (-6300 1675) $PN 1
J 0
(-6290 1685);
DISPLAY 0.680851 (-6290 1685);
PAINT MONO (-6290 1685);
FORCEPROP 2 LAST SEC_TYPE 
J 0
(-7000 3000);
DISPLAY 1.021277 (-7000 3000);
DISPLAY INVISIBLE (-7000 3000);
FORCEPROP 2 LAST CDS_LIB pure_quanta
J 0
(-6700 1925);
DISPLAY INVISIBLE (-6700 1925);
FORCEPROP 1 LAST NEEDS_NO_SIZE TRUE
J 0
(-6700 1925);
DISPLAY 0.723404 (-6700 1925);
PAINT GREEN (-6700 1925);
DISPLAY INVISIBLE (-6700 1925);
FORCEPROP 1 LAST CDS_LMAN_SYM_OUTLINE -300,700,250,-650
J 0
(-6700 1925);
DISPLAY 0.468085 (-6700 1925);
PAINT GREEN (-6700 1925);
DISPLAY INVISIBLE (-6700 1925);
FORCEPROP 1 LAST PATH I8
J 0
(-6700 1925);
DISPLAY 0.723404 (-6700 1925);
PAINT GREEN (-6700 1925);
DISPLAY INVISIBLE (-6700 1925);
FORCEPROP 2 LAST SEC 1
J 0
(-7000 3000);
DISPLAY 0.680851 (-7000 3000);
PAINT MONO (-7000 3000);
DISPLAY INVISIBLE (-7000 3000);
FORCEADD OFFPAGE..5
(-8225 1925);
FORCEPROP 2 LAST $XR0 278 
J 0
(-8480 1925);
DISPLAY 0.638298 (-8480 1925);
PAINT MONO (-8480 1925);
FORCEPROP 1 LAST COMMENT_BODY TRUE
J 0
(-8125 1850);
DISPLAY 0.872340 (-8125 1850);
PAINT GREEN (-8125 1850);
DISPLAY INVISIBLE (-8125 1850);
FORCEPROP 1 LAST OFFPAGE TRUE
J 0
(-7900 1800);
DISPLAY 0.872340 (-7900 1800);
PAINT GREEN (-7900 1800);
DISPLAY INVISIBLE (-7900 1800);
FORCEPROP 2 LAST CDS_LIB standard
J 0
(-8225 1925);
DISPLAY INVISIBLE (-8225 1925);
FORCEPROP 2 LAST PATH I9
J 0
(-8475 1975);
DISPLAY 1.021277 (-8475 1975);
DISPLAY INVISIBLE (-8475 1975);
FORCEADD DNS..1
(-8775 1300);
PAINT RED (-8775 1300);
FORCEPROP 1 LAST COMMENT_BODY TRUE
R 1
J 0
(-8700 1075);
DISPLAY 0.872340 (-8700 1075);
PAINT GREEN (-8700 1075);
DISPLAY INVISIBLE (-8700 1075);
FORCEPROP 2 LAST CDS_LIB mstr_misc
J 0
(-8775 1300);
DISPLAY INVISIBLE (-8775 1300);
FORCEADD QUANTA_TITLE_BLOCK_C..1
(-175 -1275);
FORCEPROP 0 LAST CDS_CON_LAST_MODIFIED Fri Aug 25 14:04:50 2023
J 0
(-2060 -1260);
DISPLAY INVISIBLE (-2060 -1260);
FORCEPROP 1 LAST CUSTOM_TXT_CDS <CON_LAST_MODIFIED>
J 0
(-2060 -1260);
DISPLAY 0.978723 (-2060 -1260);
FORCEPROP 2 LAST CUSTOM_TXT_CDS <XR_PAGE_TITLE>
J 0
(-8065 3975);
DISPLAY 0.638298 (-8065 3975);
PAINT PINK (-8065 3975);
DISPLAY INVISIBLE (-8065 3975);
FORCEPROP 1 LAST CUSTOM_TXT_CDS <NAME_2>
J 0
(-3350 -1225);
FORCEPROP 1 LAST CUSTOM_TXT_CDS <NAME_1>
J 0
(-3350 -1100);
FORCEPROP 1 LAST CUSTOM_TXT_CDS <Q_NUMBER>
J 0
(-1578 -1172);
DISPLAY 1.212766 (-1578 -1172);
FORCEPROP 1 LAST CUSTOM_TXT_CDS <Q_PROJ>
J 0
(-2557 -1173);
DISPLAY 1.212766 (-2557 -1173);
FORCEPROP 1 LAST CUSTOM_TXT_CDS <Q_REV>
J 0
(-359 -1172);
DISPLAY 1.212766 (-359 -1172);
FORCEPROP 1 LAST CUSTOM_TXT_CDS <CON_PAGE_NUM> OF <CON_TOTAL_PAGES>
J 0
(-621 -1257);
DISPLAY 0.978723 (-621 -1257);
FORCEPROP 1 LAST Q_TITLE VCCD_HV_CPU0 VR PHASE (2/2)
J 0
(-9475 -1225);
DISPLAY 2.446809 (-9475 -1225);
PAINT GREEN (-9475 -1225);
FORCEPROP 1 LAST Q_DEPT 
J 1
(-3938 -1226);
DISPLAY 1.957447 (-3938 -1226);
PAINT GREEN (-3938 -1226);
FORCEPROP 2 LAST CDS_XR_PAGE_TITLE CR-279 : @S9S_MB_2U_LIB.S9S_MB_2U(SCH_1):PAGE279
J 0
(-8065 3975);
DISPLAY 0.638298 (-8065 3975);
PAINT PINK (-8065 3975);
DISPLAY INVISIBLE (-8065 3975);
FORCEPROP 1 LAST CDS_LMAN_SYM_OUTLINE -9475,6775,100,-125
J 0
(-175 -1275);
DISPLAY 0.468085 (-175 -1275);
PAINT GREEN (-175 -1275);
DISPLAY INVISIBLE (-175 -1275);
FORCEPROP 2 LAST CDS_LIB pure_quanta
J 0
(-175 -1275);
DISPLAY INVISIBLE (-175 -1275);
FORCEPROP 2 LAST PAGE_BORDER TRUE
J 0
(-8065 3975);
DISPLAY 0.638298 (-8065 3975);
PAINT PINK (-8065 3975);
DISPLAY INVISIBLE (-8065 3975);
FORCEPROP 1 LAST COMMENT_BODY TRUE
J 0
(-163 -1288);
DISPLAY 0.978723 (-163 -1288);
PAINT GREEN (-163 -1288);
DISPLAY INVISIBLE (-163 -1288);
WIRE 16 -1 (-8225 3075)(-8225 3300);
WIRE 16 -1 (-8225 3075)(-7575 3075);
FORCEPROP 0 LAST SIG_NAME PVCCFA_EHV_CPU0_PVCC
J 0
(-8060 3110);
DISPLAY 0.659574 (-8060 3110);
FORCEPROP 2 LASTPROP $XR1 276 
J 0
(-8156 3146);
DISPLAY 0.638298 (-8156 3146);
PAINT MONO (-8156 3146);
FORCEPROP 2 LASTPROP $XR0 275 
J 0
(-8156 3110);
DISPLAY 0.638298 (-8156 3110);
PAINT MONO (-8156 3110);
WIRE 16 -1 (-4100 3150)(-4100 3075);
WIRE 16 -1 (-2175 550)(-2175 500);
WIRE 16 -1 (-1825 2025)(-1825 1925);
WIRE 16 -1 (-9000 1750)(-9000 1675);
WIRE 16 -1 (-9000 1750)(-8150 1750);
WIRE 16 -1 (-8775 1225)(-8775 1150);
WIRE 16 -1 (-8225 2275)(-8225 2175);
WIRE 16 -1 (-7575 2625)(-7575 2700);
WIRE 16 -1 (-6050 1325)(-6050 1250);
WIRE 16 -1 (-6050 1375)(-6050 1325);
WIRE 16 -1 (-6300 1325)(-6050 1325);
WIRE 16 -1 (-4100 2450)(-4100 2575);
WIRE 16 -1 (-2175 0)(-2175 75);
WIRE 16 -1 (-1825 1400)(-1825 1500);
WIRE 16 -1 (-2175 175)(-2175 75);
WIRE 16 -1 (-2675 175)(-2675 75);
WIRE 16 -1 (-2175 75)(-2675 75);
WIRE 16 -1 (-3150 75)(-2675 75);
WIRE 16 -1 (-3150 200)(-3150 75);
WIRE 16 -1 (-2175 375)(-2175 500);
WIRE 16 -1 (-2675 375)(-2675 500);
WIRE 16 -1 (-2175 500)(-2675 500);
WIRE 16 -1 (-3150 500)(-2675 500);
WIRE 16 -1 (-3150 400)(-3150 500);
WIRE 16 -1 (-1825 1625)(-1825 1500);
WIRE 16 -1 (-2275 1625)(-2275 1500);
WIRE 16 -1 (-1825 1500)(-2275 1500);
WIRE 16 -1 (-2825 1625)(-2825 1500);
WIRE 16 -1 (-2275 1500)(-2825 1500);
WIRE 16 -1 (-3350 1500)(-3350 1625);
WIRE 16 -1 (-3350 1500)(-2825 1500);
WIRE 16 -1 (-3350 1500)(-3750 1500);
WIRE 16 -1 (-3750 1625)(-3750 1500);
WIRE 16 -1 (-1825 1925)(-1825 1825);
WIRE 16 -1 (-2275 1825)(-2275 1925);
WIRE 16 -1 (-1825 1925)(-2275 1925);
WIRE 16 -1 (-2825 1825)(-2825 1925);
WIRE 16 -1 (-2275 1925)(-2825 1925);
WIRE 16 -1 (-3350 1925)(-3350 1825);
WIRE 16 -1 (-3350 1925)(-2825 1925);
WIRE 16 -1 (-3750 1825)(-3750 1925);
WIRE 16 -1 (-3350 1925)(-3750 1925);
WIRE 16 -1 (-4100 1925)(-3950 1925);
WIRE 16 -1 (-3750 1925)(-3950 1925);
WIRE 16 -1 (-3950 1925)(-3950 1675);
WIRE 16 -1 (-5050 1675)(-3950 1675);
WIRE 16 -1 (-6300 1925)(-4300 1925);
FORCEPROP 2 LAST SIG_NAME SW_PVCCD_HV_CPU0_SW1
J 0
(-6110 1935);
DISPLAY 0.617021 (-6110 1935);
WIRE 16 -1 (-4700 2925)(-4700 3075);
WIRE 16 -1 (-4100 3075)(-4700 3075);
WIRE 16 -1 (-5100 3075)(-5100 2925);
WIRE 16 -1 (-5100 3075)(-4700 3075);
WIRE 16 -1 (-5500 2925)(-5500 3075);
WIRE 16 -1 (-5500 3075)(-5100 3075);
WIRE 16 -1 (-5900 2925)(-5900 3075);
WIRE 16 -1 (-5900 3075)(-5500 3075);
WIRE 16 -1 (-6125 3075)(-5900 3075);
WIRE 16 -1 (-6300 2575)(-6125 2575);
WIRE 16 -1 (-6125 3075)(-6125 2575);
WIRE 16 -1 (-6125 2525)(-6125 2575);
WIRE 16 -1 (-6300 2525)(-6125 2525);
WIRE 16 -1 (-4700 2725)(-4700 2575);
WIRE 16 -1 (-4100 2575)(-4700 2575);
WIRE 16 -1 (-5100 2725)(-5100 2575);
WIRE 16 -1 (-5100 2575)(-4700 2575);
WIRE 16 -1 (-5500 2725)(-5500 2575);
WIRE 16 -1 (-5100 2575)(-5500 2575);
WIRE 16 -1 (-5900 2575)(-5500 2575);
WIRE 16 -1 (-5900 2725)(-5900 2575);
WIRE 16 -1 (-4675 2025)(-4675 2100);
WIRE 16 -1 (-6300 2025)(-4675 2025);
FORCEPROP 0 LAST CDS_PHYS_NET_NAME SW_PVCCD_HV_CPU0_BOOTR1
J 0
(-6110 2065);
PAINT MONO (-6110 2065);
DISPLAY INVISIBLE (-6110 2065);
FORCEPROP 2 LAST SIG_NAME SW_PVCCD_HV_CPU0_BOOTR1
J 0
(-6110 2035);
DISPLAY 0.617021 (-6110 2035);
WIRE 16 -1 (-4675 2375)(-4675 2300);
WIRE 16 -1 (-5350 2375)(-4675 2375);
FORCEPROP 2 LAST SIG_NAME SW_PVCCD_HV_CPU0_BOOT1_R
J 0
(-5160 2385);
DISPLAY 0.617021 (-5160 2385);
WIRE 16 -1 (-6150 2375)(-5550 2375);
FORCEPROP 0 LAST CDS_PHYS_NET_NAME SW_PVCCD_HV_CPU0_BOOT1
J 0
(-6110 2404);
PAINT MONO (-6110 2404);
DISPLAY INVISIBLE (-6110 2404);
WIRE 16 -1 (-6150 2275)(-6150 2375);
FORCEPROP 2 LAST SIG_NAME SW_PVCCD_HV_CPU0_BOOT1
J 0
(-6310 2385);
DISPLAY 0.617021 (-6310 2385);
WIRE 16 -1 (-6300 2275)(-6150 2275);
WIRE 16 -1 (-6300 1675)(-5250 1675);
FORCEPROP 2 LAST SIG_NAME PVCCD_HV_CPU0_VOS
J 0
(-6110 1685);
DISPLAY 0.638298 (-6110 1685);
WIRE 16 -1 (-6050 1475)(-6300 1475);
WIRE 16 -1 (-6300 1425)(-6050 1425);
WIRE 16 -1 (-6050 1425)(-6050 1475);
WIRE 16 -1 (-6050 1425)(-6050 1375);
WIRE 16 -1 (-6300 1375)(-6050 1375);
WIRE 16 -1 (-8225 2875)(-8225 3075);
WIRE 16 -1 (-7200 2575)(-7150 2575);
WIRE 16 -1 (-7200 3075)(-7200 2575);
WIRE 16 -1 (-7575 2900)(-7575 3075);
WIRE 16 -1 (-7575 3075)(-7200 3075);
WIRE 16 -1 (-7150 2075)(-7175 2075);
WIRE 16 -1 (-7175 2275)(-7175 2075);
WIRE 16 -1 (-7150 2275)(-7175 2275);
WIRE 16 -1 (-7800 2275)(-7175 2275);
FORCEPROP 2 LAST SIG_NAME PVCCD_HV_CPU0_VDD1
J 0
(-7785 2285);
DISPLAY 0.638298 (-7785 2285);
WIRE 16 -1 (-7800 2575)(-7800 2275);
WIRE 16 -1 (-8225 2675)(-8225 2575);
WIRE 16 -1 (-8225 2575)(-7800 2575);
WIRE 16 -1 (-8225 2475)(-8225 2575);
WIRE 16 -1 (-7150 1925)(-8175 1925);
FORCEPROP 2 LAST SIG_NAME PVCCD_HV_CPU0_ACSP1
J 0
(-7785 1935);
DISPLAY 0.617021 (-7785 1935);
WIRE 16 -1 (-7150 1325)(-8175 1325);
FORCEPROP 2 LAST SIG_NAME PVCCD_HV_CPU0_APWM1
J 0
(-7785 1335);
DISPLAY 0.617021 (-7785 1335);
WIRE 16 -1 (-7150 1425)(-8175 1425);
FORCEPROP 2 LAST SIG_NAME PVCCD_HV_CPU0_ATSEN
J 0
(-7785 1435);
DISPLAY 0.617021 (-7785 1435);
WIRE 16 -1 (-7400 1750)(-7950 1750);
WIRE 16 -1 (-8175 1825)(-7400 1825);
FORCEPROP 2 LAST SIG_NAME PVCCD_HV_CPU0_VREF
J 0
(-7785 1835);
DISPLAY 0.617021 (-7785 1835);
WIRE 16 -1 (-7400 1825)(-7400 1750);
FORCEPROP 0 LAST CDS_PHYS_NET_NAME PVCCD_HV_CPU0_VREF
J 0
(-7400 1775);
PAINT MONO (-7400 1775);
DISPLAY INVISIBLE (-7400 1775);
WIRE 16 -1 (-7400 1825)(-7150 1825);
WIRE 16 -1 (-8775 1625)(-8775 1425);
WIRE 16 -1 (-7150 1625)(-8775 1625);
FORCEPROP 2 LAST SIG_NAME PVCCD_HV_CPU0_LSET1
J 0
(-7785 1635);
DISPLAY 0.617021 (-7785 1635);
WIRE 17 273 (-3525 -175)(-1700 -175);
WIRE 17 273 (-1700 775)(-1700 -175);
WIRE 17 273 (-3525 -175)(-3525 775);
WIRE 17 273 (-3525 775)(-1700 775);
DOT 1 (-7400 1825);
DOT 1 (-8225 2575);
DOT 1 (-8225 3075);
DOT 1 (-7575 3075);
DOT 1 (-7175 2275);
DOT 1 (-6050 1325);
DOT 1 (-6050 1375);
DOT 1 (-6050 1425);
DOT 1 (-6125 2575);
DOT 1 (-5500 2575);
DOT 1 (-5900 3075);
DOT 1 (-5500 3075);
DOT 1 (-5100 2575);
DOT 1 (-4700 2575);
DOT 1 (-5100 3075);
DOT 1 (-4700 3075);
DOT 1 (-3350 1500);
DOT 1 (-2675 75);
DOT 1 (-2675 500);
DOT 1 (-2825 1500);
DOT 1 (-2275 1500);
DOT 1 (-3950 1925);
DOT 1 (-3750 1925);
DOT 1 (-3350 1925);
DOT 1 (-2825 1925);
DOT 1 (-2275 1925);
DOT 1 (-2175 75);
DOT 1 (-2175 500);
DOT 1 (-1825 1500);
DOT 1 (-1825 1925);
FORCENOTE
PVCCD_HV_CPU0_PHASE1
(-7175 3125) 0;
DISPLAY LEFT (-7175 3125);
DISPLAY 1.021277 (-7175 3125);
PAINT WHITE (-7175 3125);
FORCENOTE
APPLY TO ALL RAILS.
(-3225 1050) 0;
DISPLAY LEFT (-3225 1050);
DISPLAY 1.021277 (-3225 1050);
FORCENOTE
PGL6312.121AHLT 
(-3850 2250) 0;
DISPLAY LEFT (-3850 2250);
DISPLAY 1.021277 (-3850 2250);
FORCENOTE
6.5*6.5*10.0
(-3850 2175) 0;
DISPLAY LEFT (-3850 2175);
DISPLAY 1.021277 (-3850 2175);
FORCENOTE
DCR=0.17M OHM
(-3850 2025) 0;
DISPLAY LEFT (-3850 2025);
DISPLAY 1.021277 (-3850 2025);
FORCENOTE
ISAT=60A@100C
(-3850 2100) 0;
DISPLAY LEFT (-3850 2100);
DISPLAY 1.021277 (-3850 2100);
FORCENOTE
RESERVE BY ARCHER CITY
(-2925 850) 0;
DISPLAY LEFT (-2925 850);
DISPLAY 1.021277 (-2925 850);
PAINT WHITE (-2925 850);
FORCENOTE
(499OHM) TO ABSORB LEAKAGE FROM SPS.
(-3225 1125) 0;
DISPLAY LEFT (-3225 1125);
DISPLAY 1.021277 (-3225 1125);
FORCENOTE
RENESAS RECOMMEND BLEEDER RESISTOR
(-3225 1200) 0;
DISPLAY LEFT (-3225 1200);
DISPLAY 1.021277 (-3225 1200);
QUIT
